(kicad_pcb
	(version 20260206)
	(generator "pcbnew")
	(generator_version "10.0")
	(general
		(thickness 1.6)
		(legacy_teardrops no)
	)
	(paper "A4")
	(title_block
		(title "04192023_DAF0TMB3IC0_F0TG_MB_C_brd_V02_OCP.brd")
		(comment 1 "Grand Teton / footprints 2471-2477 of 8354")
	)
	(layers
		(0 "F.Cu" signal "TOP")
		(4 "In1.Cu" signal "GND")
		(6 "In2.Cu" signal "IN1")
		(8 "In3.Cu" signal "GND1")
		(10 "In4.Cu" signal "IN2")
		(12 "In5.Cu" signal "GND2")
		(14 "In6.Cu" signal "IN3")
		(16 "In7.Cu" signal "GND3")
		(18 "In8.Cu" signal "VCC")
		(20 "In9.Cu" signal "VCC1")
		(22 "In10.Cu" signal "GND4")
		(24 "In11.Cu" signal "IN4")
		(26 "In12.Cu" signal "GND5")
		(28 "In13.Cu" signal "IN5")
		(30 "In14.Cu" signal "GND6")
		(32 "In15.Cu" signal "IN6")
		(34 "In16.Cu" signal "GND7")
		(2 "B.Cu" signal "BOTTOM")
		(9 "F.Adhes" user "F.Adhesive")
		(11 "B.Adhes" user "B.Adhesive")
		(13 "F.Paste" user "Package Geometry/Pastemask Top")
		(15 "B.Paste" user "Package Geometry/Pastemask Bottom")
		(5 "F.SilkS" user "Ref Des/Silkscreen Top")
		(7 "B.SilkS" user "Ref Des/Silkscreen Bottom")
		(1 "F.Mask" user "Board Geometry/Soldermask Top")
		(3 "B.Mask" user "Board Geometry/Soldermask Bottom")
		(17 "Dwgs.User" user "User.Drawings")
		(19 "Cmts.User" user "User.Comments")
		(21 "Eco1.User" user "User.Eco1")
		(23 "Eco2.User" user "User.Eco2")
		(25 "Edge.Cuts" user "Board Geometry/Outline")
		(27 "Margin" user)
		(31 "F.CrtYd" user "Package Geometry/Place Bound Top")
		(29 "B.CrtYd" user "Package Geometry/Place Bound Bottom")
		(35 "F.Fab" user "Ref Des/Assembly Top")
		(33 "B.Fab" user "Ref Des/Assembly Bottom")
	)
	(footprint ""
		(layer "F.Cu")
		(at 401.471638 -168.510966 90)
		(property "Reference" "PC586_2"
			(at 0 0 90)
			(layer "F.SilkS")
			(hide yes)
			(effects
				(font
					(size 1.27 1.27)
				)
			)
		)
		(property "Value" ""
			(at 0 0 90)
			(layer "F.Fab")
			(effects
				(font
					(size 1.27 1.27)
				)
			)
		)
		(duplicate_pad_numbers_are_jumpers no)
		(fp_line
			(start 0.7874 -0.4064)
			(end 0.7874 0.4064)
			(stroke
				(width 0.1524)
				(type default)
			)
			(layer "F.SilkS")
		)
		(fp_line
			(start -0.7874 -0.4064)
			(end 0.7874 -0.4064)
			(stroke
				(width 0.1524)
				(type default)
			)
			(layer "F.SilkS")
		)
		(fp_line
			(start 0.7874 0.4064)
			(end -0.7874 0.4064)
			(stroke
				(width 0.1524)
				(type default)
			)
			(layer "F.SilkS")
		)
		(fp_line
			(start -0.7874 0.4064)
			(end -0.7874 -0.4064)
			(stroke
				(width 0.1524)
				(type default)
			)
			(layer "F.SilkS")
		)
		(fp_line
			(start -0.12065 -0.305054)
			(end -0.12065 -0.2794)
			(stroke
				(width 0.1)
				(type default)
			)
			(layer "F.Fab")
		)
		(fp_line
			(start -0.67945 -0.305054)
			(end -0.12065 -0.305054)
			(stroke
				(width 0.1)
				(type default)
			)
			(layer "F.Fab")
		)
		(fp_line
			(start 0.67945 -0.3048)
			(end 0.67945 0.3048)
			(stroke
				(width 0.1)
				(type default)
			)
			(layer "F.Fab")
		)
		(fp_line
			(start 0.12065 -0.3048)
			(end 0.67945 -0.3048)
			(stroke
				(width 0.1)
				(type default)
			)
			(layer "F.Fab")
		)
		(fp_line
			(start 0.12065 -0.2794)
			(end 0.12065 -0.3048)
			(stroke
				(width 0.1)
				(type default)
			)
			(layer "F.Fab")
		)
		(fp_line
			(start -0.12065 -0.2794)
			(end 0.12065 -0.2794)
			(stroke
				(width 0.1)
				(type default)
			)
			(layer "F.Fab")
		)
		(fp_line
			(start 0.120396 0.2794)
			(end -0.12065 0.2794)
			(stroke
				(width 0.1)
				(type default)
			)
			(layer "F.Fab")
		)
		(fp_line
			(start -0.12065 0.2794)
			(end -0.12065 0.3048)
			(stroke
				(width 0.1)
				(type default)
			)
			(layer "F.Fab")
		)
		(fp_line
			(start 0.67945 0.3048)
			(end 0.120396 0.3048)
			(stroke
				(width 0.1)
				(type default)
			)
			(layer "F.Fab")
		)
		(fp_line
			(start 0.120396 0.3048)
			(end 0.120396 0.2794)
			(stroke
				(width 0.1)
				(type default)
			)
			(layer "F.Fab")
		)
		(fp_line
			(start -0.12065 0.3048)
			(end -0.67945 0.3048)
			(stroke
				(width 0.1)
				(type default)
			)
			(layer "F.Fab")
		)
		(fp_line
			(start -0.67945 0.3048)
			(end -0.67945 -0.305054)
			(stroke
				(width 0.1)
				(type default)
			)
			(layer "F.Fab")
		)
		(pad "1" smd circle
			(at -0.40005 0 90)
			(size 0 0)
			(layers "F.Cu" "F.Mask" "F.Paste")
			(net "SW_P12V_AUX_PVDDCR_SOC_P0_FLT")
		)
		(pad "2" smd circle
			(at 0.40005 0 90)
			(size 0 0)
			(layers "F.Cu" "F.Mask" "F.Paste")
			(net "GND")
		)
	)
	(footprint ""
		(layer "F.Cu")
		(at 414.668462 -416.899344 -90)
		(property "Reference" "C6593"
			(at 0 0 270)
			(layer "F.SilkS")
			(hide yes)
			(effects
				(font
					(size 1.27 1.27)
				)
			)
		)
		(property "Value" ""
			(at 0 0 270)
			(layer "F.Fab")
			(effects
				(font
					(size 1.27 1.27)
				)
			)
		)
		(duplicate_pad_numbers_are_jumpers no)
		(fp_line
			(start -0.299974 0.150114)
			(end -0.299974 -0.150114)
			(stroke
				(width 0.1)
				(type default)
			)
			(layer "F.Fab")
		)
		(fp_line
			(start 0.299974 0.150114)
			(end -0.299974 0.150114)
			(stroke
				(width 0.1)
				(type default)
			)
			(layer "F.Fab")
		)
		(fp_line
			(start -0.299974 -0.150114)
			(end 0.299974 -0.150114)
			(stroke
				(width 0.1)
				(type default)
			)
			(layer "F.Fab")
		)
		(fp_line
			(start 0.299974 -0.150114)
			(end 0.299974 0.150114)
			(stroke
				(width 0.1)
				(type default)
			)
			(layer "F.Fab")
		)
		(pad "1" smd rect
			(at -0.2667 0 270)
			(size 0.3048 0.381)
			(layers "F.Cu" "F.Mask" "F.Paste")
			(net "P5E_CPU0_P2_TX_BUF_C_DP<14>")
		)
		(pad "2" smd rect
			(at 0.2667 0 270)
			(size 0.3048 0.381)
			(layers "F.Cu" "F.Mask" "F.Paste")
			(net "P5E_CPU0_P2_TX_BUF_DP<14>")
		)
	)
	(footprint ""
		(layer "F.Cu")
		(at 305.013106 -349.381572 90)
		(property "Reference" "PC109"
			(at 0 0 90)
			(layer "F.SilkS")
			(hide yes)
			(effects
				(font
					(size 1.27 1.27)
				)
			)
		)
		(property "Value" ""
			(at 0 0 90)
			(layer "F.Fab")
			(effects
				(font
					(size 1.27 1.27)
				)
			)
		)
		(duplicate_pad_numbers_are_jumpers no)
		(fp_line
			(start 0.7874 -0.4064)
			(end 0.7874 0.4064)
			(stroke
				(width 0.1524)
				(type default)
			)
			(layer "F.SilkS")
		)
		(fp_line
			(start -0.7874 -0.4064)
			(end 0.7874 -0.4064)
			(stroke
				(width 0.1524)
				(type default)
			)
			(layer "F.SilkS")
		)
		(fp_line
			(start 0.7874 0.4064)
			(end 0.376428 0.4064)
			(stroke
				(width 0.1524)
				(type default)
			)
			(layer "F.SilkS")
		)
		(fp_line
			(start -0.156972 0.4064)
			(end -0.7874 0.4064)
			(stroke
				(width 0.1524)
				(type default)
			)
			(layer "F.SilkS")
		)
		(fp_line
			(start -0.7874 0.4064)
			(end -0.7874 -0.4064)
			(stroke
				(width 0.1524)
				(type default)
			)
			(layer "F.SilkS")
		)
		(fp_line
			(start -0.12065 -0.305054)
			(end -0.12065 -0.2794)
			(stroke
				(width 0.1)
				(type default)
			)
			(layer "F.Fab")
		)
		(fp_line
			(start -0.67945 -0.305054)
			(end -0.12065 -0.305054)
			(stroke
				(width 0.1)
				(type default)
			)
			(layer "F.Fab")
		)
		(fp_line
			(start 0.67945 -0.3048)
			(end 0.67945 0.3048)
			(stroke
				(width 0.1)
				(type default)
			)
			(layer "F.Fab")
		)
		(fp_line
			(start 0.12065 -0.3048)
			(end 0.67945 -0.3048)
			(stroke
				(width 0.1)
				(type default)
			)
			(layer "F.Fab")
		)
		(fp_line
			(start 0.12065 -0.2794)
			(end 0.12065 -0.3048)
			(stroke
				(width 0.1)
				(type default)
			)
			(layer "F.Fab")
		)
		(fp_line
			(start -0.12065 -0.2794)
			(end 0.12065 -0.2794)
			(stroke
				(width 0.1)
				(type default)
			)
			(layer "F.Fab")
		)
		(fp_line
			(start 0.120396 0.2794)
			(end -0.12065 0.2794)
			(stroke
				(width 0.1)
				(type default)
			)
			(layer "F.Fab")
		)
		(fp_line
			(start -0.12065 0.2794)
			(end -0.12065 0.3048)
			(stroke
				(width 0.1)
				(type default)
			)
			(layer "F.Fab")
		)
		(fp_line
			(start 0.67945 0.3048)
			(end 0.120396 0.3048)
			(stroke
				(width 0.1)
				(type default)
			)
			(layer "F.Fab")
		)
		(fp_line
			(start 0.120396 0.3048)
			(end 0.120396 0.2794)
			(stroke
				(width 0.1)
				(type default)
			)
			(layer "F.Fab")
		)
		(fp_line
			(start -0.12065 0.3048)
			(end -0.67945 0.3048)
			(stroke
				(width 0.1)
				(type default)
			)
			(layer "F.Fab")
		)
		(fp_line
			(start -0.67945 0.3048)
			(end -0.67945 -0.305054)
			(stroke
				(width 0.1)
				(type default)
			)
			(layer "F.Fab")
		)
		(pad "1" smd circle
			(at -0.40005 0 90)
			(size 0 0)
			(layers "F.Cu" "F.Mask" "F.Paste")
			(net "PVDDCR_CPU1_P0_VCC4")
		)
		(pad "2" smd circle
			(at 0.40005 0 90)
			(size 0 0)
			(layers "F.Cu" "F.Mask" "F.Paste")
			(net "GND")
		)
	)
	(footprint ""
		(layer "F.Cu")
		(at 277.352252 -118.89867)
		(property "Reference" "R3583"
			(at 0 0 0)
			(layer "F.SilkS")
			(hide yes)
			(effects
				(font
					(size 1.27 1.27)
				)
			)
		)
		(property "Value" ""
			(at 0 0 0)
			(layer "F.Fab")
			(effects
				(font
					(size 1.27 1.27)
				)
			)
		)
		(duplicate_pad_numbers_are_jumpers no)
		(fp_line
			(start -0.7874 -0.4064)
			(end 0.7874 -0.4064)
			(stroke
				(width 0.1524)
				(type default)
			)
			(layer "F.SilkS")
		)
		(fp_line
			(start -0.7874 0.4064)
			(end -0.7874 -0.4064)
			(stroke
				(width 0.1524)
				(type default)
			)
			(layer "F.SilkS")
		)
		(fp_line
			(start 0.7874 -0.4064)
			(end 0.7874 0.4064)
			(stroke
				(width 0.1524)
				(type default)
			)
			(layer "F.SilkS")
		)
		(fp_line
			(start 0.7874 0.4064)
			(end -0.7874 0.4064)
			(stroke
				(width 0.1524)
				(type default)
			)
			(layer "F.SilkS")
		)
		(fp_line
			(start -0.67945 -0.305054)
			(end -0.12065 -0.305054)
			(stroke
				(width 0.1)
				(type default)
			)
			(layer "F.Fab")
		)
		(fp_line
			(start -0.67945 0.3048)
			(end -0.67945 -0.305054)
			(stroke
				(width 0.1)
				(type default)
			)
			(layer "F.Fab")
		)
		(fp_line
			(start -0.12065 -0.305054)
			(end -0.12065 -0.2794)
			(stroke
				(width 0.1)
				(type default)
			)
			(layer "F.Fab")
		)
		(fp_line
			(start -0.12065 -0.2794)
			(end 0.12065 -0.2794)
			(stroke
				(width 0.1)
				(type default)
			)
			(layer "F.Fab")
		)
		(fp_line
			(start -0.12065 0.2794)
			(end -0.12065 0.3048)
			(stroke
				(width 0.1)
				(type default)
			)
			(layer "F.Fab")
		)
		(fp_line
			(start -0.12065 0.3048)
			(end -0.67945 0.3048)
			(stroke
				(width 0.1)
				(type default)
			)
			(layer "F.Fab")
		)
		(fp_line
			(start 0.120396 0.2794)
			(end -0.12065 0.2794)
			(stroke
				(width 0.1)
				(type default)
			)
			(layer "F.Fab")
		)
		(fp_line
			(start 0.120396 0.3048)
			(end 0.120396 0.2794)
			(stroke
				(width 0.1)
				(type default)
			)
			(layer "F.Fab")
		)
		(fp_line
			(start 0.12065 -0.3048)
			(end 0.67945 -0.3048)
			(stroke
				(width 0.1)
				(type default)
			)
			(layer "F.Fab")
		)
		(fp_line
			(start 0.12065 -0.2794)
			(end 0.12065 -0.3048)
			(stroke
				(width 0.1)
				(type default)
			)
			(layer "F.Fab")
		)
		(fp_line
			(start 0.67945 -0.3048)
			(end 0.67945 0.3048)
			(stroke
				(width 0.1)
				(type default)
			)
			(layer "F.Fab")
		)
		(fp_line
			(start 0.67945 0.3048)
			(end 0.120396 0.3048)
			(stroke
				(width 0.1)
				(type default)
			)
			(layer "F.Fab")
		)
		(pad "1" smd circle
			(at -0.40005 0)
			(size 0 0)
			(layers "F.Cu" "F.Mask" "F.Paste")
			(net "P3V3_AUX")
		)
		(pad "2" smd circle
			(at 0.40005 0)
			(size 0 0)
			(layers "F.Cu" "F.Mask" "F.Paste")
			(net "SMB_IOEXP_3V3AUX_SDA")
		)
	)
	(footprint ""
		(layer "F.Cu")
		(at 123.725178 -72.829166 90)
		(property "Reference" "R6244"
			(at 0 0 90)
			(layer "F.SilkS")
			(hide yes)
			(effects
				(font
					(size 1.27 1.27)
				)
			)
		)
		(property "Value" ""
			(at 0 0 90)
			(layer "F.Fab")
			(effects
				(font
					(size 1.27 1.27)
				)
			)
		)
		(duplicate_pad_numbers_are_jumpers no)
		(fp_line
			(start 0.7874 -0.4064)
			(end 0.7874 0.4064)
			(stroke
				(width 0.1524)
				(type default)
			)
			(layer "F.SilkS")
		)
		(fp_line
			(start -0.7874 -0.4064)
			(end 0.7874 -0.4064)
			(stroke
				(width 0.1524)
				(type default)
			)
			(layer "F.SilkS")
		)
		(fp_line
			(start 0.7874 0.4064)
			(end -0.7874 0.4064)
			(stroke
				(width 0.1524)
				(type default)
			)
			(layer "F.SilkS")
		)
		(fp_line
			(start -0.7874 0.4064)
			(end -0.7874 -0.4064)
			(stroke
				(width 0.1524)
				(type default)
			)
			(layer "F.SilkS")
		)
		(fp_line
			(start -0.12065 -0.305054)
			(end -0.12065 -0.2794)
			(stroke
				(width 0.1)
				(type default)
			)
			(layer "F.Fab")
		)
		(fp_line
			(start -0.67945 -0.305054)
			(end -0.12065 -0.305054)
			(stroke
				(width 0.1)
				(type default)
			)
			(layer "F.Fab")
		)
		(fp_line
			(start 0.67945 -0.3048)
			(end 0.67945 0.3048)
			(stroke
				(width 0.1)
				(type default)
			)
			(layer "F.Fab")
		)
		(fp_line
			(start 0.12065 -0.3048)
			(end 0.67945 -0.3048)
			(stroke
				(width 0.1)
				(type default)
			)
			(layer "F.Fab")
		)
		(fp_line
			(start 0.12065 -0.2794)
			(end 0.12065 -0.3048)
			(stroke
				(width 0.1)
				(type default)
			)
			(layer "F.Fab")
		)
		(fp_line
			(start -0.12065 -0.2794)
			(end 0.12065 -0.2794)
			(stroke
				(width 0.1)
				(type default)
			)
			(layer "F.Fab")
		)
		(fp_line
			(start 0.120396 0.2794)
			(end -0.12065 0.2794)
			(stroke
				(width 0.1)
				(type default)
			)
			(layer "F.Fab")
		)
		(fp_line
			(start -0.12065 0.2794)
			(end -0.12065 0.3048)
			(stroke
				(width 0.1)
				(type default)
			)
			(layer "F.Fab")
		)
		(fp_line
			(start 0.67945 0.3048)
			(end 0.120396 0.3048)
			(stroke
				(width 0.1)
				(type default)
			)
			(layer "F.Fab")
		)
		(fp_line
			(start 0.120396 0.3048)
			(end 0.120396 0.2794)
			(stroke
				(width 0.1)
				(type default)
			)
			(layer "F.Fab")
		)
		(fp_line
			(start -0.12065 0.3048)
			(end -0.67945 0.3048)
			(stroke
				(width 0.1)
				(type default)
			)
			(layer "F.Fab")
		)
		(fp_line
			(start -0.67945 0.3048)
			(end -0.67945 -0.305054)
			(stroke
				(width 0.1)
				(type default)
			)
			(layer "F.Fab")
		)
		(pad "1" smd circle
			(at -0.40005 0 90)
			(size 0 0)
			(layers "F.Cu" "F.Mask" "F.Paste")
			(net "P3V3_AUX")
		)
		(pad "2" smd circle
			(at 0.40005 0 90)
			(size 0 0)
			(layers "F.Cu" "F.Mask" "F.Paste")
			(net "PWRGD_P1V2_AUX")
		)
	)
	(footprint ""
		(layer "F.Cu")
		(at 439.272172 -32.173418 90)
		(property "Reference" "PC2156"
			(at 0 0 90)
			(layer "F.SilkS")
			(hide yes)
			(effects
				(font
					(size 1.27 1.27)
				)
			)
		)
		(property "Value" ""
			(at 0 0 90)
			(layer "F.Fab")
			(effects
				(font
					(size 1.27 1.27)
				)
			)
		)
		(duplicate_pad_numbers_are_jumpers no)
		(fp_line
			(start 0.7874 -0.4064)
			(end 0.7874 0.4064)
			(stroke
				(width 0.1524)
				(type default)
			)
			(layer "F.SilkS")
		)
		(fp_line
			(start -0.7874 -0.4064)
			(end 0.7874 -0.4064)
			(stroke
				(width 0.1524)
				(type default)
			)
			(layer "F.SilkS")
		)
		(fp_line
			(start 0.7874 0.4064)
			(end -0.7874 0.4064)
			(stroke
				(width 0.1524)
				(type default)
			)
			(layer "F.SilkS")
		)
		(fp_line
			(start -0.7874 0.4064)
			(end -0.7874 -0.4064)
			(stroke
				(width 0.1524)
				(type default)
			)
			(layer "F.SilkS")
		)
		(fp_line
			(start -0.12065 -0.305054)
			(end -0.12065 -0.2794)
			(stroke
				(width 0.1)
				(type default)
			)
			(layer "F.Fab")
		)
		(fp_line
			(start -0.67945 -0.305054)
			(end -0.12065 -0.305054)
			(stroke
				(width 0.1)
				(type default)
			)
			(layer "F.Fab")
		)
		(fp_line
			(start 0.67945 -0.3048)
			(end 0.67945 0.3048)
			(stroke
				(width 0.1)
				(type default)
			)
			(layer "F.Fab")
		)
		(fp_line
			(start 0.12065 -0.3048)
			(end 0.67945 -0.3048)
			(stroke
				(width 0.1)
				(type default)
			)
			(layer "F.Fab")
		)
		(fp_line
			(start 0.12065 -0.2794)
			(end 0.12065 -0.3048)
			(stroke
				(width 0.1)
				(type default)
			)
			(layer "F.Fab")
		)
		(fp_line
			(start -0.12065 -0.2794)
			(end 0.12065 -0.2794)
			(stroke
				(width 0.1)
				(type default)
			)
			(layer "F.Fab")
		)
		(fp_line
			(start 0.120396 0.2794)
			(end -0.12065 0.2794)
			(stroke
				(width 0.1)
				(type default)
			)
			(layer "F.Fab")
		)
		(fp_line
			(start -0.12065 0.2794)
			(end -0.12065 0.3048)
			(stroke
				(width 0.1)
				(type default)
			)
			(layer "F.Fab")
		)
		(fp_line
			(start 0.67945 0.3048)
			(end 0.120396 0.3048)
			(stroke
				(width 0.1)
				(type default)
			)
			(layer "F.Fab")
		)
		(fp_line
			(start 0.120396 0.3048)
			(end 0.120396 0.2794)
			(stroke
				(width 0.1)
				(type default)
			)
			(layer "F.Fab")
		)
		(fp_line
			(start -0.12065 0.3048)
			(end -0.67945 0.3048)
			(stroke
				(width 0.1)
				(type default)
			)
			(layer "F.Fab")
		)
		(fp_line
			(start -0.67945 0.3048)
			(end -0.67945 -0.305054)
			(stroke
				(width 0.1)
				(type default)
			)
			(layer "F.Fab")
		)
		(pad "1" smd circle
			(at -0.40005 0 90)
			(size 0 0)
			(layers "F.Cu" "F.Mask" "F.Paste")
			(net "P12V_OCP_IMON_1")
		)
		(pad "2" smd circle
			(at 0.40005 0 90)
			(size 0 0)
			(layers "F.Cu" "F.Mask" "F.Paste")
			(net "GND")
		)
	)
	(footprint ""
		(layer "F.Cu")
		(at 298.967144 -390.77646 180)
		(property "Reference" "C933"
			(at 0 0 180)
			(layer "F.SilkS")
			(hide yes)
			(effects
				(font
					(size 1.27 1.27)
				)
			)
		)
		(property "Value" ""
			(at 0 0 180)
			(layer "F.Fab")
			(effects
				(font
					(size 1.27 1.27)
				)
			)
		)
		(duplicate_pad_numbers_are_jumpers no)
		(fp_line
			(start 0.299974 0.150114)
			(end -0.299974 0.150114)
			(stroke
				(width 0.1)
				(type default)
			)
			(layer "F.Fab")
		)
		(fp_line
			(start 0.299974 -0.150114)
			(end 0.299974 0.150114)
			(stroke
				(width 0.1)
				(type default)
			)
			(layer "F.Fab")
		)
		(fp_line
			(start -0.299974 0.150114)
			(end -0.299974 -0.150114)
			(stroke
				(width 0.1)
				(type default)
			)
			(layer "F.Fab")
		)
		(fp_line
			(start -0.299974 -0.150114)
			(end 0.299974 -0.150114)
			(stroke
				(width 0.1)
				(type default)
			)
			(layer "F.Fab")
		)
		(pad "1" smd rect
			(at -0.2667 0 180)
			(size 0.3048 0.381)
			(layers "F.Cu" "F.Mask" "F.Paste")
			(net "P5E_CPU0_P0_TX_C_DP<0>")
		)
		(pad "2" smd rect
			(at 0.2667 0 180)
			(size 0.3048 0.381)
			(layers "F.Cu" "F.Mask" "F.Paste")
			(net "P5E_CPU0_P0_TX_DP<0>")
		)
	)
)
